(kicad_pcb
	(version 20260206)
	(generator "pcbnew")
	(generator_version "10.0")
	(general
		(thickness 1.6)
		(legacy_teardrops no)
	)
	(paper "A4")
	(title_block
		(title "01162023_DA0F0TEBIF0_F0T_Expander_BD_F_brd_V02_OCP.brd")
		(comment 1 "Grand Teton / footprints 3450-3455 of 9728")
	)
	(layers
		(0 "F.Cu" signal "TOP")
		(4 "In1.Cu" signal "GND")
		(6 "In2.Cu" signal "VCC")
		(8 "In3.Cu" signal "VCC1")
		(10 "In4.Cu" signal "GND1")
		(12 "In5.Cu" signal "IN1")
		(14 "In6.Cu" signal "GND2")
		(16 "In7.Cu" signal "IN2")
		(18 "In8.Cu" signal "GND3")
		(20 "In9.Cu" signal "IN3")
		(22 "In10.Cu" signal "GND4")
		(24 "In11.Cu" signal "IN4")
		(26 "In12.Cu" signal "GND5")
		(28 "In13.Cu" signal "IN5")
		(30 "In14.Cu" signal "GND6")
		(32 "In15.Cu" signal "IN6")
		(34 "In16.Cu" signal "GND7")
		(2 "B.Cu" signal "BOTTOM")
		(9 "F.Adhes" user "F.Adhesive")
		(11 "B.Adhes" user "B.Adhesive")
		(13 "F.Paste" user "Package Geometry/Pastemask Top")
		(15 "B.Paste" user "Package Geometry/Pastemask Bottom")
		(5 "F.SilkS" user "Ref Des/Silkscreen Top")
		(7 "B.SilkS" user "Ref Des/Silkscreen Bottom")
		(1 "F.Mask" user "Board Geometry/Soldermask Top")
		(3 "B.Mask" user "Board Geometry/Soldermask Bottom")
		(17 "Dwgs.User" user "User.Drawings")
		(19 "Cmts.User" user "User.Comments")
		(21 "Eco1.User" user "User.Eco1")
		(23 "Eco2.User" user "User.Eco2")
		(25 "Edge.Cuts" user "Board Geometry/Outline")
		(27 "Margin" user)
		(31 "F.CrtYd" user "Package Geometry/Place Bound Top")
		(29 "B.CrtYd" user "Package Geometry/Place Bound Bottom")
		(35 "F.Fab" user "Ref Des/Assembly Top")
		(33 "B.Fab" user "Ref Des/Assembly Bottom")
	)
	(footprint ""
		(layer "F.Cu")
		(at 192.483486 -49.94148)
		(property "Reference" "R577"
			(at 0 0 0)
			(layer "F.SilkS")
			(hide yes)
			(effects
				(font
					(size 1.27 1.27)
				)
			)
		)
		(property "Value" ""
			(at 0 0 0)
			(layer "F.Fab")
			(effects
				(font
					(size 1.27 1.27)
				)
			)
		)
		(duplicate_pad_numbers_are_jumpers no)
		(fp_line
			(start -0.7874 -0.4064)
			(end 0.7874 -0.4064)
			(stroke
				(width 0.1524)
				(type default)
			)
			(layer "F.SilkS")
		)
		(fp_line
			(start -0.7874 0.4064)
			(end -0.7874 -0.4064)
			(stroke
				(width 0.1524)
				(type default)
			)
			(layer "F.SilkS")
		)
		(fp_line
			(start 0.7874 -0.4064)
			(end 0.7874 0.4064)
			(stroke
				(width 0.1524)
				(type default)
			)
			(layer "F.SilkS")
		)
		(fp_line
			(start 0.7874 0.4064)
			(end -0.7874 0.4064)
			(stroke
				(width 0.1524)
				(type default)
			)
			(layer "F.SilkS")
		)
		(fp_line
			(start -0.67945 -0.305054)
			(end -0.12065 -0.305054)
			(stroke
				(width 0.1)
				(type default)
			)
			(layer "F.Fab")
		)
		(fp_line
			(start -0.67945 0.3048)
			(end -0.67945 -0.305054)
			(stroke
				(width 0.1)
				(type default)
			)
			(layer "F.Fab")
		)
		(fp_line
			(start -0.12065 -0.305054)
			(end -0.12065 -0.2794)
			(stroke
				(width 0.1)
				(type default)
			)
			(layer "F.Fab")
		)
		(fp_line
			(start -0.12065 -0.2794)
			(end 0.12065 -0.2794)
			(stroke
				(width 0.1)
				(type default)
			)
			(layer "F.Fab")
		)
		(fp_line
			(start -0.12065 0.2794)
			(end -0.12065 0.3048)
			(stroke
				(width 0.1)
				(type default)
			)
			(layer "F.Fab")
		)
		(fp_line
			(start -0.12065 0.3048)
			(end -0.67945 0.3048)
			(stroke
				(width 0.1)
				(type default)
			)
			(layer "F.Fab")
		)
		(fp_line
			(start 0.120396 0.2794)
			(end -0.12065 0.2794)
			(stroke
				(width 0.1)
				(type default)
			)
			(layer "F.Fab")
		)
		(fp_line
			(start 0.120396 0.3048)
			(end 0.120396 0.2794)
			(stroke
				(width 0.1)
				(type default)
			)
			(layer "F.Fab")
		)
		(fp_line
			(start 0.12065 -0.3048)
			(end 0.67945 -0.3048)
			(stroke
				(width 0.1)
				(type default)
			)
			(layer "F.Fab")
		)
		(fp_line
			(start 0.12065 -0.2794)
			(end 0.12065 -0.3048)
			(stroke
				(width 0.1)
				(type default)
			)
			(layer "F.Fab")
		)
		(fp_line
			(start 0.67945 -0.3048)
			(end 0.67945 0.3048)
			(stroke
				(width 0.1)
				(type default)
			)
			(layer "F.Fab")
		)
		(fp_line
			(start 0.67945 0.3048)
			(end 0.120396 0.3048)
			(stroke
				(width 0.1)
				(type default)
			)
			(layer "F.Fab")
		)
		(pad "1" smd circle
			(at -0.40005 0)
			(size 0 0)
			(layers "F.Cu" "F.Mask" "F.Paste")
			(net "SMB_BIC_I2C6_MUX_SSD_0_7_ADC_R_SCL")
		)
		(pad "2" smd circle
			(at 0.40005 0)
			(size 0 0)
			(layers "F.Cu" "F.Mask" "F.Paste")
			(net "SMB_SSD6_ADC_SCL")
		)
	)
	(footprint ""
		(layer "F.Cu")
		(at 443.551818 -230.203756 90)
		(property "Reference" "C4442"
			(at 0 0 90)
			(layer "F.SilkS")
			(hide yes)
			(effects
				(font
					(size 1.27 1.27)
				)
			)
		)
		(property "Value" ""
			(at 0 0 90)
			(layer "F.Fab")
			(effects
				(font
					(size 1.27 1.27)
				)
			)
		)
		(duplicate_pad_numbers_are_jumpers no)
		(fp_line
			(start 1.2954 -0.5842)
			(end 1.2954 0.5842)
			(stroke
				(width 0.1524)
				(type default)
			)
			(layer "F.SilkS")
		)
		(fp_line
			(start -1.2954 -0.5842)
			(end 1.2954 -0.5842)
			(stroke
				(width 0.1524)
				(type default)
			)
			(layer "F.SilkS")
		)
		(fp_line
			(start 1.2954 0.5842)
			(end -1.2954 0.5842)
			(stroke
				(width 0.1524)
				(type default)
			)
			(layer "F.SilkS")
		)
		(fp_line
			(start -1.2954 0.5842)
			(end -1.2954 -0.5842)
			(stroke
				(width 0.1524)
				(type default)
			)
			(layer "F.SilkS")
		)
		(fp_line
			(start 0.8636 -0.4572)
			(end 0.8636 -0.4064)
			(stroke
				(width 0.1)
				(type default)
			)
			(layer "F.Fab")
		)
		(fp_line
			(start -0.8636 -0.4572)
			(end 0.8636 -0.4572)
			(stroke
				(width 0.1)
				(type default)
			)
			(layer "F.Fab")
		)
		(fp_line
			(start 1.1938 -0.4064)
			(end 1.1938 0.4064)
			(stroke
				(width 0.1)
				(type default)
			)
			(layer "F.Fab")
		)
		(fp_line
			(start 0.8636 -0.4064)
			(end 1.1938 -0.4064)
			(stroke
				(width 0.1)
				(type default)
			)
			(layer "F.Fab")
		)
		(fp_line
			(start -0.8636 -0.4064)
			(end -0.8636 -0.4572)
			(stroke
				(width 0.1)
				(type default)
			)
			(layer "F.Fab")
		)
		(fp_line
			(start -1.1938 -0.4064)
			(end -0.8636 -0.4064)
			(stroke
				(width 0.1)
				(type default)
			)
			(layer "F.Fab")
		)
		(fp_line
			(start 1.1938 0.4064)
			(end 0.8636 0.4064)
			(stroke
				(width 0.1)
				(type default)
			)
			(layer "F.Fab")
		)
		(fp_line
			(start 0.8636 0.4064)
			(end 0.8636 0.4572)
			(stroke
				(width 0.1)
				(type default)
			)
			(layer "F.Fab")
		)
		(fp_line
			(start -0.8636 0.4064)
			(end -1.1938 0.4064)
			(stroke
				(width 0.1)
				(type default)
			)
			(layer "F.Fab")
		)
		(fp_line
			(start -1.1938 0.4064)
			(end -1.1938 -0.4064)
			(stroke
				(width 0.1)
				(type default)
			)
			(layer "F.Fab")
		)
		(fp_line
			(start 0.8636 0.4572)
			(end -0.8636 0.4572)
			(stroke
				(width 0.1)
				(type default)
			)
			(layer "F.Fab")
		)
		(fp_line
			(start -0.8636 0.4572)
			(end -0.8636 0.4064)
			(stroke
				(width 0.1)
				(type default)
			)
			(layer "F.Fab")
		)
		(pad "1" smd rect
			(at -0.7366 0)
			(size 0.7112 0.8128)
			(layers "F.Cu" "F.Mask" "F.Paste")
			(net "P3V3_AUX")
		)
		(pad "2" smd rect
			(at 0.7366 0)
			(size 0.7112 0.8128)
			(layers "F.Cu" "F.Mask" "F.Paste")
			(net "GND")
		)
	)
	(footprint ""
		(layer "F.Cu")
		(at 441.303918 -291.722048 90)
		(property "Reference" "C2760"
			(at 0 0 90)
			(layer "F.SilkS")
			(hide yes)
			(effects
				(font
					(size 1.27 1.27)
				)
			)
		)
		(property "Value" ""
			(at 0 0 90)
			(layer "F.Fab")
			(effects
				(font
					(size 1.27 1.27)
				)
			)
		)
		(duplicate_pad_numbers_are_jumpers no)
		(fp_line
			(start 0.7874 -0.4064)
			(end 0.7874 0.4064)
			(stroke
				(width 0.1524)
				(type default)
			)
			(layer "F.SilkS")
		)
		(fp_line
			(start -0.7874 -0.4064)
			(end 0.7874 -0.4064)
			(stroke
				(width 0.1524)
				(type default)
			)
			(layer "F.SilkS")
		)
		(fp_line
			(start 0.7874 0.4064)
			(end -0.7874 0.4064)
			(stroke
				(width 0.1524)
				(type default)
			)
			(layer "F.SilkS")
		)
		(fp_line
			(start -0.7874 0.4064)
			(end -0.7874 -0.4064)
			(stroke
				(width 0.1524)
				(type default)
			)
			(layer "F.SilkS")
		)
		(fp_line
			(start -0.12065 -0.305054)
			(end -0.12065 -0.2794)
			(stroke
				(width 0.1)
				(type default)
			)
			(layer "F.Fab")
		)
		(fp_line
			(start -0.67945 -0.305054)
			(end -0.12065 -0.305054)
			(stroke
				(width 0.1)
				(type default)
			)
			(layer "F.Fab")
		)
		(fp_line
			(start 0.67945 -0.3048)
			(end 0.67945 0.3048)
			(stroke
				(width 0.1)
				(type default)
			)
			(layer "F.Fab")
		)
		(fp_line
			(start 0.12065 -0.3048)
			(end 0.67945 -0.3048)
			(stroke
				(width 0.1)
				(type default)
			)
			(layer "F.Fab")
		)
		(fp_line
			(start 0.12065 -0.2794)
			(end 0.12065 -0.3048)
			(stroke
				(width 0.1)
				(type default)
			)
			(layer "F.Fab")
		)
		(fp_line
			(start -0.12065 -0.2794)
			(end 0.12065 -0.2794)
			(stroke
				(width 0.1)
				(type default)
			)
			(layer "F.Fab")
		)
		(fp_line
			(start 0.120396 0.2794)
			(end -0.12065 0.2794)
			(stroke
				(width 0.1)
				(type default)
			)
			(layer "F.Fab")
		)
		(fp_line
			(start -0.12065 0.2794)
			(end -0.12065 0.3048)
			(stroke
				(width 0.1)
				(type default)
			)
			(layer "F.Fab")
		)
		(fp_line
			(start 0.67945 0.3048)
			(end 0.120396 0.3048)
			(stroke
				(width 0.1)
				(type default)
			)
			(layer "F.Fab")
		)
		(fp_line
			(start 0.120396 0.3048)
			(end 0.120396 0.2794)
			(stroke
				(width 0.1)
				(type default)
			)
			(layer "F.Fab")
		)
		(fp_line
			(start -0.12065 0.3048)
			(end -0.67945 0.3048)
			(stroke
				(width 0.1)
				(type default)
			)
			(layer "F.Fab")
		)
		(fp_line
			(start -0.67945 0.3048)
			(end -0.67945 -0.305054)
			(stroke
				(width 0.1)
				(type default)
			)
			(layer "F.Fab")
		)
		(pad "1" smd circle
			(at -0.40005 0 90)
			(size 0 0)
			(layers "F.Cu" "F.Mask" "F.Paste")
			(net "GND")
		)
		(pad "2" smd circle
			(at 0.40005 0 90)
			(size 0 0)
			(layers "F.Cu" "F.Mask" "F.Paste")
			(net "P3V3_AUX")
		)
	)
	(footprint ""
		(layer "F.Cu")
		(at 383.495042 -59.577986 90)
		(property "Reference" "PC567"
			(at 0 0 90)
			(layer "F.SilkS")
			(hide yes)
			(effects
				(font
					(size 1.27 1.27)
				)
			)
		)
		(property "Value" ""
			(at 0 0 90)
			(layer "F.Fab")
			(effects
				(font
					(size 1.27 1.27)
				)
			)
		)
		(duplicate_pad_numbers_are_jumpers no)
		(fp_line
			(start 0.7874 -0.4064)
			(end 0.7874 0.4064)
			(stroke
				(width 0.1524)
				(type default)
			)
			(layer "F.SilkS")
		)
		(fp_line
			(start -0.7874 -0.4064)
			(end 0.7874 -0.4064)
			(stroke
				(width 0.1524)
				(type default)
			)
			(layer "F.SilkS")
		)
		(fp_line
			(start 0.7874 0.4064)
			(end -0.7874 0.4064)
			(stroke
				(width 0.1524)
				(type default)
			)
			(layer "F.SilkS")
		)
		(fp_line
			(start -0.7874 0.4064)
			(end -0.7874 -0.4064)
			(stroke
				(width 0.1524)
				(type default)
			)
			(layer "F.SilkS")
		)
		(fp_line
			(start -0.12065 -0.305054)
			(end -0.12065 -0.2794)
			(stroke
				(width 0.1)
				(type default)
			)
			(layer "F.Fab")
		)
		(fp_line
			(start -0.67945 -0.305054)
			(end -0.12065 -0.305054)
			(stroke
				(width 0.1)
				(type default)
			)
			(layer "F.Fab")
		)
		(fp_line
			(start 0.67945 -0.3048)
			(end 0.67945 0.3048)
			(stroke
				(width 0.1)
				(type default)
			)
			(layer "F.Fab")
		)
		(fp_line
			(start 0.12065 -0.3048)
			(end 0.67945 -0.3048)
			(stroke
				(width 0.1)
				(type default)
			)
			(layer "F.Fab")
		)
		(fp_line
			(start 0.12065 -0.2794)
			(end 0.12065 -0.3048)
			(stroke
				(width 0.1)
				(type default)
			)
			(layer "F.Fab")
		)
		(fp_line
			(start -0.12065 -0.2794)
			(end 0.12065 -0.2794)
			(stroke
				(width 0.1)
				(type default)
			)
			(layer "F.Fab")
		)
		(fp_line
			(start 0.120396 0.2794)
			(end -0.12065 0.2794)
			(stroke
				(width 0.1)
				(type default)
			)
			(layer "F.Fab")
		)
		(fp_line
			(start -0.12065 0.2794)
			(end -0.12065 0.3048)
			(stroke
				(width 0.1)
				(type default)
			)
			(layer "F.Fab")
		)
		(fp_line
			(start 0.67945 0.3048)
			(end 0.120396 0.3048)
			(stroke
				(width 0.1)
				(type default)
			)
			(layer "F.Fab")
		)
		(fp_line
			(start 0.120396 0.3048)
			(end 0.120396 0.2794)
			(stroke
				(width 0.1)
				(type default)
			)
			(layer "F.Fab")
		)
		(fp_line
			(start -0.12065 0.3048)
			(end -0.67945 0.3048)
			(stroke
				(width 0.1)
				(type default)
			)
			(layer "F.Fab")
		)
		(fp_line
			(start -0.67945 0.3048)
			(end -0.67945 -0.305054)
			(stroke
				(width 0.1)
				(type default)
			)
			(layer "F.Fab")
		)
		(pad "1" smd circle
			(at -0.40005 0 90)
			(size 0 0)
			(layers "F.Cu" "F.Mask" "F.Paste")
			(net "P3V3_SSD13_SS")
		)
		(pad "2" smd circle
			(at 0.40005 0 90)
			(size 0 0)
			(layers "F.Cu" "F.Mask" "F.Paste")
			(net "GND")
		)
	)
	(footprint ""
		(layer "F.Cu")
		(at 313.056016 -32.848042 -90)
		(property "Reference" "R6091"
			(at 0 0 270)
			(layer "F.SilkS")
			(hide yes)
			(effects
				(font
					(size 1.27 1.27)
				)
			)
		)
		(property "Value" ""
			(at 0 0 270)
			(layer "F.Fab")
			(effects
				(font
					(size 1.27 1.27)
				)
			)
		)
		(duplicate_pad_numbers_are_jumpers no)
		(fp_line
			(start -0.7874 0.4064)
			(end -0.7874 -0.4064)
			(stroke
				(width 0.1524)
				(type default)
			)
			(layer "F.SilkS")
		)
		(fp_line
			(start 0.7874 0.4064)
			(end -0.7874 0.4064)
			(stroke
				(width 0.1524)
				(type default)
			)
			(layer "F.SilkS")
		)
		(fp_line
			(start -0.7874 -0.4064)
			(end 0.7874 -0.4064)
			(stroke
				(width 0.1524)
				(type default)
			)
			(layer "F.SilkS")
		)
		(fp_line
			(start 0.7874 -0.4064)
			(end 0.7874 0.4064)
			(stroke
				(width 0.1524)
				(type default)
			)
			(layer "F.SilkS")
		)
		(fp_line
			(start -0.67945 0.3048)
			(end -0.67945 -0.305054)
			(stroke
				(width 0.1)
				(type default)
			)
			(layer "F.Fab")
		)
		(fp_line
			(start -0.12065 0.3048)
			(end -0.67945 0.3048)
			(stroke
				(width 0.1)
				(type default)
			)
			(layer "F.Fab")
		)
		(fp_line
			(start 0.120396 0.3048)
			(end 0.120396 0.2794)
			(stroke
				(width 0.1)
				(type default)
			)
			(layer "F.Fab")
		)
		(fp_line
			(start 0.67945 0.3048)
			(end 0.120396 0.3048)
			(stroke
				(width 0.1)
				(type default)
			)
			(layer "F.Fab")
		)
		(fp_line
			(start -0.12065 0.2794)
			(end -0.12065 0.3048)
			(stroke
				(width 0.1)
				(type default)
			)
			(layer "F.Fab")
		)
		(fp_line
			(start 0.120396 0.2794)
			(end -0.12065 0.2794)
			(stroke
				(width 0.1)
				(type default)
			)
			(layer "F.Fab")
		)
		(fp_line
			(start -0.12065 -0.2794)
			(end 0.12065 -0.2794)
			(stroke
				(width 0.1)
				(type default)
			)
			(layer "F.Fab")
		)
		(fp_line
			(start 0.12065 -0.2794)
			(end 0.12065 -0.3048)
			(stroke
				(width 0.1)
				(type default)
			)
			(layer "F.Fab")
		)
		(fp_line
			(start 0.12065 -0.3048)
			(end 0.67945 -0.3048)
			(stroke
				(width 0.1)
				(type default)
			)
			(layer "F.Fab")
		)
		(fp_line
			(start 0.67945 -0.3048)
			(end 0.67945 0.3048)
			(stroke
				(width 0.1)
				(type default)
			)
			(layer "F.Fab")
		)
		(fp_line
			(start -0.67945 -0.305054)
			(end -0.12065 -0.305054)
			(stroke
				(width 0.1)
				(type default)
			)
			(layer "F.Fab")
		)
		(fp_line
			(start -0.12065 -0.305054)
			(end -0.12065 -0.2794)
			(stroke
				(width 0.1)
				(type default)
			)
			(layer "F.Fab")
		)
		(pad "1" smd circle
			(at -0.40005 0 270)
			(size 0 0)
			(layers "F.Cu" "F.Mask" "F.Paste")
			(net "SSD11_AUX_P3V3_EN_R")
		)
		(pad "2" smd circle
			(at 0.40005 0 270)
			(size 0 0)
			(layers "F.Cu" "F.Mask" "F.Paste")
			(net "P3V3_SSD11_CO_EN")
		)
	)
	(footprint ""
		(layer "F.Cu")
		(at 196.554852 -22.961346 90)
		(property "Reference" "R1673"
			(at 0 0 90)
			(layer "F.SilkS")
			(hide yes)
			(effects
				(font
					(size 1.27 1.27)
				)
			)
		)
		(property "Value" ""
			(at 0 0 90)
			(layer "F.Fab")
			(effects
				(font
					(size 1.27 1.27)
				)
			)
		)
		(duplicate_pad_numbers_are_jumpers no)
		(fp_line
			(start 0.7874 -0.4064)
			(end 0.7874 0.4064)
			(stroke
				(width 0.1524)
				(type default)
			)
			(layer "F.SilkS")
		)
		(fp_line
			(start -0.7874 -0.4064)
			(end 0.7874 -0.4064)
			(stroke
				(width 0.1524)
				(type default)
			)
			(layer "F.SilkS")
		)
		(fp_line
			(start 0.7874 0.4064)
			(end -0.7874 0.4064)
			(stroke
				(width 0.1524)
				(type default)
			)
			(layer "F.SilkS")
		)
		(fp_line
			(start -0.7874 0.4064)
			(end -0.7874 -0.4064)
			(stroke
				(width 0.1524)
				(type default)
			)
			(layer "F.SilkS")
		)
		(fp_line
			(start -0.12065 -0.305054)
			(end -0.12065 -0.2794)
			(stroke
				(width 0.1)
				(type default)
			)
			(layer "F.Fab")
		)
		(fp_line
			(start -0.67945 -0.305054)
			(end -0.12065 -0.305054)
			(stroke
				(width 0.1)
				(type default)
			)
			(layer "F.Fab")
		)
		(fp_line
			(start 0.67945 -0.3048)
			(end 0.67945 0.3048)
			(stroke
				(width 0.1)
				(type default)
			)
			(layer "F.Fab")
		)
		(fp_line
			(start 0.12065 -0.3048)
			(end 0.67945 -0.3048)
			(stroke
				(width 0.1)
				(type default)
			)
			(layer "F.Fab")
		)
		(fp_line
			(start 0.12065 -0.2794)
			(end 0.12065 -0.3048)
			(stroke
				(width 0.1)
				(type default)
			)
			(layer "F.Fab")
		)
		(fp_line
			(start -0.12065 -0.2794)
			(end 0.12065 -0.2794)
			(stroke
				(width 0.1)
				(type default)
			)
			(layer "F.Fab")
		)
		(fp_line
			(start 0.120396 0.2794)
			(end -0.12065 0.2794)
			(stroke
				(width 0.1)
				(type default)
			)
			(layer "F.Fab")
		)
		(fp_line
			(start -0.12065 0.2794)
			(end -0.12065 0.3048)
			(stroke
				(width 0.1)
				(type default)
			)
			(layer "F.Fab")
		)
		(fp_line
			(start 0.67945 0.3048)
			(end 0.120396 0.3048)
			(stroke
				(width 0.1)
				(type default)
			)
			(layer "F.Fab")
		)
		(fp_line
			(start 0.120396 0.3048)
			(end 0.120396 0.2794)
			(stroke
				(width 0.1)
				(type default)
			)
			(layer "F.Fab")
		)
		(fp_line
			(start -0.12065 0.3048)
			(end -0.67945 0.3048)
			(stroke
				(width 0.1)
				(type default)
			)
			(layer "F.Fab")
		)
		(fp_line
			(start -0.67945 0.3048)
			(end -0.67945 -0.305054)
			(stroke
				(width 0.1)
				(type default)
			)
			(layer "F.Fab")
		)
		(pad "1" smd circle
			(at -0.40005 0 90)
			(size 0 0)
			(layers "F.Cu" "F.Mask" "F.Paste")
			(net "SMB_SSD6_ISO_EN")
		)
		(pad "2" smd circle
			(at 0.40005 0 90)
			(size 0 0)
			(layers "F.Cu" "F.Mask" "F.Paste")
			(net "P3V3_AUX")
		)
	)
)
